(kicad_pcb
	(version 20260206)
	(generator "pcbnew")
	(generator_version "10.0")
	(general
		(thickness 1.6)
		(legacy_teardrops no)
	)
	(paper "A4")
	(title_block
		(title "01162023_DA0F0TEBIF0_F0T_Expander_BD_F_brd_V02_OCP.brd")
		(comment 1 "Grand Teton / footprints 5410-5411 of 9728")
	)
	(layers
		(0 "F.Cu" signal "TOP")
		(4 "In1.Cu" signal "GND")
		(6 "In2.Cu" signal "VCC")
		(8 "In3.Cu" signal "VCC1")
		(10 "In4.Cu" signal "GND1")
		(12 "In5.Cu" signal "IN1")
		(14 "In6.Cu" signal "GND2")
		(16 "In7.Cu" signal "IN2")
		(18 "In8.Cu" signal "GND3")
		(20 "In9.Cu" signal "IN3")
		(22 "In10.Cu" signal "GND4")
		(24 "In11.Cu" signal "IN4")
		(26 "In12.Cu" signal "GND5")
		(28 "In13.Cu" signal "IN5")
		(30 "In14.Cu" signal "GND6")
		(32 "In15.Cu" signal "IN6")
		(34 "In16.Cu" signal "GND7")
		(2 "B.Cu" signal "BOTTOM")
		(9 "F.Adhes" user "F.Adhesive")
		(11 "B.Adhes" user "B.Adhesive")
		(13 "F.Paste" user "Package Geometry/Pastemask Top")
		(15 "B.Paste" user "Package Geometry/Pastemask Bottom")
		(5 "F.SilkS" user "Ref Des/Silkscreen Top")
		(7 "B.SilkS" user "Ref Des/Silkscreen Bottom")
		(1 "F.Mask" user "Board Geometry/Soldermask Top")
		(3 "B.Mask" user "Board Geometry/Soldermask Bottom")
		(17 "Dwgs.User" user "User.Drawings")
		(19 "Cmts.User" user "User.Comments")
		(21 "Eco1.User" user "User.Eco1")
		(23 "Eco2.User" user "User.Eco2")
		(25 "Edge.Cuts" user "Board Geometry/Outline")
		(27 "Margin" user)
		(31 "F.CrtYd" user "Package Geometry/Place Bound Top")
		(29 "B.CrtYd" user "Package Geometry/Place Bound Bottom")
		(35 "F.Fab" user "Ref Des/Assembly Top")
		(33 "B.Fab" user "Ref Des/Assembly Bottom")
	)
	(footprint ""
		(layer "F.Cu")
		(at 64.964818 -26.785062 180)
		(property "Reference" "J32"
			(at 4.986274 -10.940796 90)
			(unlocked yes)
			(layer "F.SilkS")
			(effects
				(font
					(size 0.7874 0.5842)
					(thickness 0.1524)
				)
			)
		)
		(property "Value" ""
			(at 0 0 180)
			(layer "F.Fab")
			(effects
				(font
					(size 1.27 1.27)
				)
			)
		)
		(duplicate_pad_numbers_are_jumpers no)
		(fp_line
			(start 3.150108 12.115038)
			(end 1.529334 12.115038)
			(stroke
				(width 0.1524)
				(type default)
			)
			(layer "F.SilkS")
		)
		(fp_line
			(start 3.074924 12.014962)
			(end 1.632204 12.014962)
			(stroke
				(width 0.1524)
				(type default)
			)
			(layer "F.SilkS")
		)
		(fp_line
			(start 1.632204 -12.014962)
			(end 3.074924 -12.014962)
			(stroke
				(width 0.1524)
				(type default)
			)
			(layer "F.SilkS")
		)
		(fp_line
			(start 1.529334 -12.115038)
			(end 3.150108 -12.115038)
			(stroke
				(width 0.1524)
				(type default)
			)
			(layer "F.SilkS")
		)
		(fp_line
			(start -1.529334 12.115038)
			(end -3.150108 12.115038)
			(stroke
				(width 0.1524)
				(type default)
			)
			(layer "F.SilkS")
		)
		(fp_line
			(start -1.632204 12.014962)
			(end -3.074924 12.014962)
			(stroke
				(width 0.1524)
				(type default)
			)
			(layer "F.SilkS")
		)
		(fp_line
			(start -3.074924 -12.014962)
			(end -1.632204 -12.014962)
			(stroke
				(width 0.1524)
				(type default)
			)
			(layer "F.SilkS")
		)
		(fp_line
			(start -3.150108 -12.115038)
			(end -1.529334 -12.115038)
			(stroke
				(width 0.1524)
				(type default)
			)
			(layer "F.SilkS")
		)
		(fp_poly
			(pts
				(xy 3.54711 -8.888476) (xy 3.969512 -10.15619) (xy 4.81457 -9.311132)
			)
			(stroke
				(width 0)
				(type default)
			)
			(fill yes)
			(layer "F.SilkS")
		)
		(fp_line
			(start 3.074924 12.014962)
			(end -3.074924 12.014962)
			(stroke
				(width 0.1)
				(type default)
			)
			(layer "F.Fab")
		)
		(fp_line
			(start 3.074924 -12.014962)
			(end 3.074924 12.014962)
			(stroke
				(width 0.1)
				(type default)
			)
			(layer "F.Fab")
		)
		(fp_line
			(start -3.074924 12.014962)
			(end -3.074924 -12.014962)
			(stroke
				(width 0.1)
				(type default)
			)
			(layer "F.Fab")
		)
		(fp_line
			(start -3.074924 -12.014962)
			(end 3.074924 -12.014962)
			(stroke
				(width 0.1)
				(type default)
			)
			(layer "F.Fab")
		)
		(fp_poly
			(pts
				(xy 3.348736 -7.994904) (xy 4.543806 -8.592566) (xy 4.543806 -7.397496)
			)
			(stroke
				(width 0)
				(type default)
			)
			(fill yes)
			(layer "F.Fab")
		)
		(pad "" np_thru_hole circle
			(at -1.75006 -9.815068 90)
			(size 1.1176 1.1176)
			(drill 1.1176)
			(layers "*.Cu" "*.Mask")
			(clearance 0.381)
			(thermal_gap 0.381)
		)
		(pad "" np_thru_hole circle
			(at 0 9.815068 90)
			(size 1.1176 1.1176)
			(drill 1.1176)
			(layers "*.Cu" "*.Mask")
			(clearance 0.381)
			(thermal_gap 0.381)
		)
		(pad "A1" smd rect
			(at 2.29997 -7.994904 90)
			(size 0.381 1.27)
			(layers "F.Cu" "F.Mask" "F.Paste")
			(net "GND")
		)
		(pad "A2" smd rect
			(at 2.29997 -7.394956 90)
			(size 0.381 1.27)
			(layers "F.Cu" "F.Mask" "F.Paste")
			(net "GND")
		)
		(pad "A3" smd rect
			(at 2.29997 -6.795008 90)
			(size 0.381 1.27)
			(layers "F.Cu" "F.Mask" "F.Paste")
			(net "GND")
		)
		(pad "A4" smd rect
			(at 2.29997 -6.19506 90)
			(size 0.381 1.27)
			(layers "F.Cu" "F.Mask" "F.Paste")
			(net "GND")
		)
		(pad "A5" smd rect
			(at 2.29997 -5.595112 90)
			(size 0.381 1.27)
			(layers "F.Cu" "F.Mask" "F.Paste")
			(net "GND")
		)
		(pad "A6" smd rect
			(at 2.29997 -4.99491 90)
			(size 0.381 1.27)
			(layers "F.Cu" "F.Mask" "F.Paste")
			(net "GND")
		)
		(pad "A7" smd rect
			(at 2.29997 -4.394962 90)
			(size 0.381 1.27)
			(layers "F.Cu" "F.Mask" "F.Paste")
			(net "SMB_ISO_SSD2_R_SCL")
		)
		(pad "A8" smd rect
			(at 2.29997 -3.795014 90)
			(size 0.381 1.27)
			(layers "F.Cu" "F.Mask" "F.Paste")
			(net "SMB_ISO_SSD2_R_SDA")
		)
		(pad "A9" smd rect
			(at 2.29997 -3.195066 90)
			(size 0.381 1.27)
			(layers "F.Cu" "F.Mask" "F.Paste")
			(net "RST_SMB_SSD2_ISO_R_N")
		)
		(pad "A10" smd rect
			(at 2.29997 -2.595118 90)
			(size 0.381 1.27)
			(layers "F.Cu" "F.Mask" "F.Paste")
			(net "SSD2_LED_ISO_R_N")
		)
		(pad "A11" smd rect
			(at 2.29997 -1.994916 90)
			(size 0.381 1.27)
			(layers "F.Cu" "F.Mask" "F.Paste")
			(net "PU_CLKREQ2")
		)
		(pad "A12" smd rect
			(at 2.29997 -1.394968 90)
			(size 0.381 1.27)
			(layers "F.Cu" "F.Mask" "F.Paste")
			(net "PRSNT_SSD2_N")
		)
		(pad "A13" smd rect
			(at 2.29997 -0.79502 90)
			(size 0.381 1.27)
			(layers "F.Cu" "F.Mask" "F.Paste")
			(net "GND")
		)
		(pad "A14" smd rect
			(at 2.29997 -0.195072 90)
			(size 0.381 1.27)
			(layers "F.Cu" "F.Mask" "F.Paste")
			(net "Net_8573")
		)
		(pad "A15" smd rect
			(at 2.29997 0.404876 90)
			(size 0.381 1.27)
			(layers "F.Cu" "F.Mask" "F.Paste")
			(net "Net_8572")
		)
		(pad "A16" smd rect
			(at 2.29997 1.005078 90)
			(size 0.381 1.27)
			(layers "F.Cu" "F.Mask" "F.Paste")
			(net "GND")
		)
		(pad "A17" smd rect
			(at 2.29997 1.605026 90)
			(size 0.381 1.27)
			(layers "F.Cu" "F.Mask" "F.Paste")
			(net "P5E_PEX0_STN2_RX_DN<36>")
		)
		(pad "A18" smd rect
			(at 2.29997 2.204974 90)
			(size 0.381 1.27)
			(layers "F.Cu" "F.Mask" "F.Paste")
			(net "P5E_PEX0_STN2_RX_DP<36>")
		)
		(pad "A19" smd rect
			(at 2.29997 2.804922 90)
			(size 0.381 1.27)
			(layers "F.Cu" "F.Mask" "F.Paste")
			(net "GND")
		)
		(pad "A20" smd rect
			(at 2.29997 3.405124 90)
			(size 0.381 1.27)
			(layers "F.Cu" "F.Mask" "F.Paste")
			(net "P5E_PEX0_STN2_RX_DN<37>")
		)
		(pad "A21" smd rect
			(at 2.29997 4.005072 90)
			(size 0.381 1.27)
			(layers "F.Cu" "F.Mask" "F.Paste")
			(net "P5E_PEX0_STN2_RX_DP<37>")
		)
		(pad "A22" smd rect
			(at 2.29997 4.60502 90)
			(size 0.381 1.27)
			(layers "F.Cu" "F.Mask" "F.Paste")
			(net "GND")
		)
		(pad "A23" smd rect
			(at 2.29997 5.204968 90)
			(size 0.381 1.27)
			(layers "F.Cu" "F.Mask" "F.Paste")
			(net "P5E_PEX0_STN2_RX_DN<38>")
		)
		(pad "A24" smd rect
			(at 2.29997 5.804916 90)
			(size 0.381 1.27)
			(layers "F.Cu" "F.Mask" "F.Paste")
			(net "P5E_PEX0_STN2_RX_DP<38>")
		)
		(pad "A25" smd rect
			(at 2.29997 6.405118 90)
			(size 0.381 1.27)
			(layers "F.Cu" "F.Mask" "F.Paste")
			(net "GND")
		)
		(pad "A26" smd rect
			(at 2.29997 7.005066 90)
			(size 0.381 1.27)
			(layers "F.Cu" "F.Mask" "F.Paste")
			(net "P5E_PEX0_STN2_RX_DN<39>")
		)
		(pad "A27" smd rect
			(at 2.29997 7.605014 90)
			(size 0.381 1.27)
			(layers "F.Cu" "F.Mask" "F.Paste")
			(net "P5E_PEX0_STN2_RX_DP<39>")
		)
		(pad "A28" smd rect
			(at 2.29997 8.204962 90)
			(size 0.381 1.27)
			(layers "F.Cu" "F.Mask" "F.Paste")
			(net "GND")
		)
		(pad "B1" smd rect
			(at -2.29997 -7.994904 90)
			(size 0.381 1.27)
			(layers "F.Cu" "F.Mask" "F.Paste")
			(net "P12V_SSD2")
		)
		(pad "B2" smd rect
			(at -2.29997 -7.394956 90)
			(size 0.381 1.27)
			(layers "F.Cu" "F.Mask" "F.Paste")
			(net "P12V_SSD2")
		)
		(pad "B3" smd rect
			(at -2.29997 -6.795008 90)
			(size 0.381 1.27)
			(layers "F.Cu" "F.Mask" "F.Paste")
			(net "P12V_SSD2")
		)
		(pad "B4" smd rect
			(at -2.29997 -6.19506 90)
			(size 0.381 1.27)
			(layers "F.Cu" "F.Mask" "F.Paste")
			(net "P12V_SSD2")
		)
		(pad "B5" smd rect
			(at -2.29997 -5.595112 90)
			(size 0.381 1.27)
			(layers "F.Cu" "F.Mask" "F.Paste")
			(net "P12V_SSD2")
		)
		(pad "B6" smd rect
			(at -2.29997 -4.99491 90)
			(size 0.381 1.27)
			(layers "F.Cu" "F.Mask" "F.Paste")
			(net "P12V_SSD2")
		)
		(pad "B7" smd rect
			(at -2.29997 -4.394962 90)
			(size 0.381 1.27)
			(layers "F.Cu" "F.Mask" "F.Paste")
			(net "Net_8574")
		)
		(pad "B8" smd rect
			(at -2.29997 -3.795014 90)
			(size 0.381 1.27)
			(layers "F.Cu" "F.Mask" "F.Paste")
			(net "Net_8571")
		)
		(pad "B9" smd rect
			(at -2.29997 -3.195066 90)
			(size 0.381 1.27)
			(layers "F.Cu" "F.Mask" "F.Paste")
			(net "DUALPORT_N_SSD2")
		)
		(pad "B10" smd rect
			(at -2.29997 -2.595118 90)
			(size 0.381 1.27)
			(layers "F.Cu" "F.Mask" "F.Paste")
			(net "RST_SSD2_PERST_R_N")
		)
		(pad "B11" smd rect
			(at -2.29997 -1.994916 90)
			(size 0.381 1.27)
			(layers "F.Cu" "F.Mask" "F.Paste")
			(net "P3V3_SSD2")
		)
		(pad "B12" smd rect
			(at -2.29997 -1.394968 90)
			(size 0.381 1.27)
			(layers "F.Cu" "F.Mask" "F.Paste")
			(net "SSD2_PWRDIS_R")
		)
		(pad "B13" smd rect
			(at -2.29997 -0.79502 90)
			(size 0.381 1.27)
			(layers "F.Cu" "F.Mask" "F.Paste")
			(net "GND")
		)
		(pad "B14" smd rect
			(at -2.29997 -0.195072 90)
			(size 0.381 1.27)
			(layers "F.Cu" "F.Mask" "F.Paste")
			(net "CLK_100M_DB800ZL_SSD2_R_DN")
		)
		(pad "B15" smd rect
			(at -2.29997 0.404876 90)
			(size 0.381 1.27)
			(layers "F.Cu" "F.Mask" "F.Paste")
			(net "CLK_100M_DB800ZL_SSD2_R_DP")
		)
		(pad "B16" smd rect
			(at -2.29997 1.005078 90)
			(size 0.381 1.27)
			(layers "F.Cu" "F.Mask" "F.Paste")
			(net "GND")
		)
		(pad "B17" smd rect
			(at -2.29997 1.605026 90)
			(size 0.381 1.27)
			(layers "F.Cu" "F.Mask" "F.Paste")
			(net "P5E_PEX0_STN2_TX_C_DN<36>")
		)
		(pad "B18" smd rect
			(at -2.29997 2.204974 90)
			(size 0.381 1.27)
			(layers "F.Cu" "F.Mask" "F.Paste")
			(net "P5E_PEX0_STN2_TX_C_DP<36>")
		)
		(pad "B19" smd rect
			(at -2.29997 2.804922 90)
			(size 0.381 1.27)
			(layers "F.Cu" "F.Mask" "F.Paste")
			(net "GND")
		)
		(pad "B20" smd rect
			(at -2.29997 3.405124 90)
			(size 0.381 1.27)
			(layers "F.Cu" "F.Mask" "F.Paste")
			(net "P5E_PEX0_STN2_TX_C_DN<37>")
		)
		(pad "B21" smd rect
			(at -2.29997 4.005072 90)
			(size 0.381 1.27)
			(layers "F.Cu" "F.Mask" "F.Paste")
			(net "P5E_PEX0_STN2_TX_C_DP<37>")
		)
		(pad "B22" smd rect
			(at -2.29997 4.60502 90)
			(size 0.381 1.27)
			(layers "F.Cu" "F.Mask" "F.Paste")
			(net "GND")
		)
		(pad "B23" smd rect
			(at -2.29997 5.204968 90)
			(size 0.381 1.27)
			(layers "F.Cu" "F.Mask" "F.Paste")
			(net "P5E_PEX0_STN2_TX_C_DN<38>")
		)
		(pad "B24" smd rect
			(at -2.29997 5.804916 90)
			(size 0.381 1.27)
			(layers "F.Cu" "F.Mask" "F.Paste")
			(net "P5E_PEX0_STN2_TX_C_DP<38>")
		)
		(pad "B25" smd rect
			(at -2.29997 6.405118 90)
			(size 0.381 1.27)
			(layers "F.Cu" "F.Mask" "F.Paste")
			(net "GND")
		)
		(pad "B26" smd rect
			(at -2.29997 7.005066 90)
			(size 0.381 1.27)
			(layers "F.Cu" "F.Mask" "F.Paste")
			(net "P5E_PEX0_STN2_TX_C_DN<39>")
		)
		(pad "B27" smd rect
			(at -2.29997 7.605014 90)
			(size 0.381 1.27)
			(layers "F.Cu" "F.Mask" "F.Paste")
			(net "P5E_PEX0_STN2_TX_C_DP<39>")
		)
		(pad "B28" smd rect
			(at -2.29997 8.204962 90)
			(size 0.381 1.27)
			(layers "F.Cu" "F.Mask" "F.Paste")
			(net "GND")
		)
		(pad "G1" thru_hole oval
			(at 0 -11.364976 90)
			(size 1.6256 3.4798)
			(drill oval 1.1176 2.4638)
			(layers "*.Cu" "*.Mask")
			(remove_unused_layers no)
			(net "GND")
			(clearance 0.127)
			(thermal_gap 0.127)
		)
		(pad "G2" thru_hole oval
			(at 0 11.364976 90)
			(size 1.6256 3.4798)
			(drill oval 1.1176 2.4638)
			(layers "*.Cu" "*.Mask")
			(remove_unused_layers no)
			(net "GND")
			(clearance 0.127)
			(thermal_gap 0.127)
		)
		(zone
			(layer "F.Cu")
			(hatch none 0.5)
			(connect_pads
				(clearance 0)
			)
			(min_thickness 0.25)
			(keepout
				(tracks not_allowed)
				(vias allowed)
				(pads allowed)
				(copperpour not_allowed)
				(footprints allowed)
			)
			(placement
				(enabled no)
				(sheetname "")
			)
			(fill
				(thermal_gap 0.5)
				(thermal_bridge_width 0.5)
				(island_removal_mode 0)
			)
			(polygon
				(pts
					(xy 66.3448 -38.850062) (xy 63.594742 -38.850062) (xy 63.594742 -35.900106) (xy 66.3448 -35.900106)
				)
			)
		)
		(zone
			(layer "F.Cu")
			(hatch none 0.5)
			(connect_pads
				(clearance 0)
			)
			(min_thickness 0.25)
			(keepout
				(tracks not_allowed)
				(vias allowed)
				(pads allowed)
				(copperpour not_allowed)
				(footprints allowed)
			)
			(placement
				(enabled no)
				(sheetname "")
			)
			(fill
				(thermal_gap 0.5)
				(thermal_bridge_width 0.5)
				(island_removal_mode 0)
			)
			(polygon
				(pts
					(xy 67.414902 -17.670018) (xy 63.584836 -17.670018) (xy 63.584836 -14.720062) (xy 67.414902 -14.720062)
				)
			)
		)
		(zone
			(layers "F.Cu" "B.Cu" "In1.Cu" "In2.Cu" "In3.Cu" "In4.Cu" "In5.Cu" "In6.Cu"
				"In7.Cu" "In8.Cu" "In9.Cu" "In10.Cu" "In11.Cu" "In12.Cu" "In13.Cu" "In14.Cu"
				"In15.Cu" "In16.Cu"
			)
			(hatch none 0.5)
			(connect_pads
				(clearance 0)
			)
			(min_thickness 0.25)
			(keepout
				(tracks not_allowed)
				(vias allowed)
				(pads allowed)
				(copperpour not_allowed)
				(footprints allowed)
			)
			(placement
				(enabled no)
				(sheetname "")
			)
			(fill
				(thermal_gap 0.5)
				(thermal_bridge_width 0.5)
				(island_removal_mode 0)
			)
			(polygon
				(pts
					(arc
						(start 65.930018 -36.60013)
						(mid 63.999618 -36.60013)
						(end 65.930018 -36.60013)
					)
				)
			)
		)
		(zone
			(layers "F.Cu" "B.Cu" "In1.Cu" "In2.Cu" "In3.Cu" "In4.Cu" "In5.Cu" "In6.Cu"
				"In7.Cu" "In8.Cu" "In9.Cu" "In10.Cu" "In11.Cu" "In12.Cu" "In13.Cu" "In14.Cu"
				"In15.Cu" "In16.Cu"
			)
			(hatch none 0.5)
			(connect_pads
				(clearance 0)
			)
			(min_thickness 0.25)
			(keepout
				(tracks not_allowed)
				(vias allowed)
				(pads allowed)
				(copperpour not_allowed)
				(footprints allowed)
			)
			(placement
				(enabled no)
				(sheetname "")
			)
			(fill
				(thermal_gap 0.5)
				(thermal_bridge_width 0.5)
				(island_removal_mode 0)
			)
			(polygon
				(pts
					(arc
						(start 67.680078 -16.969994)
						(mid 65.749678 -16.969994)
						(end 67.680078 -16.969994)
					)
				)
			)
		)
	)
	(footprint ""
		(layer "F.Cu")
		(at 79.314802 -79.58201 90)
		(property "Reference" "R100"
			(at 0 0 90)
			(layer "F.SilkS")
			(hide yes)
			(effects
				(font
					(size 1.27 1.27)
				)
			)
		)
		(property "Value" ""
			(at 0 0 90)
			(layer "F.Fab")
			(effects
				(font
					(size 1.27 1.27)
				)
			)
		)
		(duplicate_pad_numbers_are_jumpers no)
		(fp_line
			(start 0.7874 -0.4064)
			(end 0.7874 0.4064)
			(stroke
				(width 0.1524)
				(type default)
			)
			(layer "F.SilkS")
		)
		(fp_line
			(start -0.7874 -0.4064)
			(end 0.7874 -0.4064)
			(stroke
				(width 0.1524)
				(type default)
			)
			(layer "F.SilkS")
		)
		(fp_line
			(start 0.7874 0.4064)
			(end -0.7874 0.4064)
			(stroke
				(width 0.1524)
				(type default)
			)
			(layer "F.SilkS")
		)
		(fp_line
			(start -0.7874 0.4064)
			(end -0.7874 -0.4064)
			(stroke
				(width 0.1524)
				(type default)
			)
			(layer "F.SilkS")
		)
		(fp_line
			(start -0.12065 -0.305054)
			(end -0.12065 -0.2794)
			(stroke
				(width 0.1)
				(type default)
			)
			(layer "F.Fab")
		)
		(fp_line
			(start -0.67945 -0.305054)
			(end -0.12065 -0.305054)
			(stroke
				(width 0.1)
				(type default)
			)
			(layer "F.Fab")
		)
		(fp_line
			(start 0.67945 -0.3048)
			(end 0.67945 0.3048)
			(stroke
				(width 0.1)
				(type default)
			)
			(layer "F.Fab")
		)
		(fp_line
			(start 0.12065 -0.3048)
			(end 0.67945 -0.3048)
			(stroke
				(width 0.1)
				(type default)
			)
			(layer "F.Fab")
		)
		(fp_line
			(start 0.12065 -0.2794)
			(end 0.12065 -0.3048)
			(stroke
				(width 0.1)
				(type default)
			)
			(layer "F.Fab")
		)
		(fp_line
			(start -0.12065 -0.2794)
			(end 0.12065 -0.2794)
			(stroke
				(width 0.1)
				(type default)
			)
			(layer "F.Fab")
		)
		(fp_line
			(start 0.120396 0.2794)
			(end -0.12065 0.2794)
			(stroke
				(width 0.1)
				(type default)
			)
			(layer "F.Fab")
		)
		(fp_line
			(start -0.12065 0.2794)
			(end -0.12065 0.3048)
			(stroke
				(width 0.1)
				(type default)
			)
			(layer "F.Fab")
		)
		(fp_line
			(start 0.67945 0.3048)
			(end 0.120396 0.3048)
			(stroke
				(width 0.1)
				(type default)
			)
			(layer "F.Fab")
		)
		(fp_line
			(start 0.120396 0.3048)
			(end 0.120396 0.2794)
			(stroke
				(width 0.1)
				(type default)
			)
			(layer "F.Fab")
		)
		(fp_line
			(start -0.12065 0.3048)
			(end -0.67945 0.3048)
			(stroke
				(width 0.1)
				(type default)
			)
			(layer "F.Fab")
		)
		(fp_line
			(start -0.67945 0.3048)
			(end -0.67945 -0.305054)
			(stroke
				(width 0.1)
				(type default)
			)
			(layer "F.Fab")
		)
		(pad "1" smd circle
			(at -0.40005 0 90)
			(size 0 0)
			(layers "F.Cu" "F.Mask" "F.Paste")
			(net "P3V3_NIC1")
		)
		(pad "2" smd circle
			(at 0.40005 0 90)
			(size 0 0)
			(layers "F.Cu" "F.Mask" "F.Paste")
			(net "HP_NIC1_PWRGD")
		)
	)
)
